# T6G (Grand Teton) — schematic netlist excerpt (pin names and nets, part order shuffled) for the footprints in the layout excerpt that follows; sources: Cadence DE-HDL packaged netlist, KiCad conversion of 04192023_DAF0TMB3IC0_F0TG_MB_C_brd_V02_OCP.brd

C6628  Q_CAP_DIFFBUS  DIFF BUS_0.22UF 6.3V 20% X6S  pkg C0201  page 308 : \1\ = P5E_CPU0_P3_TX_BUF_C_DN<15> ; \2\ = P5E_CPU0_P3_TX_BUF_DN<15>
C325  Q_CAP  4.7UF 6.3V 20% X6S  pkg 0402  page 334 : A = P0V9_CPU1_RT1_2A ; B = GND
C2198  Q_CAP  22UF 4V 20% X6S  pkg C0402  page 69 : A = PVDDCR_CPU0_P0 ; B = GND

(kicad_pcb
	(version 20260206)
	(generator "pcbnew")
	(generator_version "10.0")
	(general
		(thickness 1.6)
		(legacy_teardrops no)
	)
	(paper "A4")
	(title_block
		(title "04192023_DAF0TMB3IC0_F0TG_MB_C_brd_V02_OCP.brd")
		(comment 1 "Grand Teton / footprints 5148-5150 of 8354")
	)
	(layers
		(0 "F.Cu" signal "TOP")
		(4 "In1.Cu" signal "GND")
		(6 "In2.Cu" signal "IN1")
		(8 "In3.Cu" signal "GND1")
		(10 "In4.Cu" signal "IN2")
		(12 "In5.Cu" signal "GND2")
		(14 "In6.Cu" signal "IN3")
		(16 "In7.Cu" signal "GND3")
		(18 "In8.Cu" signal "VCC")
		(20 "In9.Cu" signal "VCC1")
		(22 "In10.Cu" signal "GND4")
		(24 "In11.Cu" signal "IN4")
		(26 "In12.Cu" signal "GND5")
		(28 "In13.Cu" signal "IN5")
		(30 "In14.Cu" signal "GND6")
		(32 "In15.Cu" signal "IN6")
		(34 "In16.Cu" signal "GND7")
		(2 "B.Cu" signal "BOTTOM")
		(9 "F.Adhes" user "F.Adhesive")
		(11 "B.Adhes" user "B.Adhesive")
		(13 "F.Paste" user "Package Geometry/Pastemask Top")
		(15 "B.Paste" user "Package Geometry/Pastemask Bottom")
		(5 "F.SilkS" user "Ref Des/Silkscreen Top")
		(7 "B.SilkS" user "Ref Des/Silkscreen Bottom")
		(1 "F.Mask" user "Board Geometry/Soldermask Top")
		(3 "B.Mask" user "Board Geometry/Soldermask Bottom")
		(17 "Dwgs.User" user "User.Drawings")
		(19 "Cmts.User" user "User.Comments")
		(21 "Eco1.User" user "User.Eco1")
		(23 "Eco2.User" user "User.Eco2")
		(25 "Edge.Cuts" user "Board Geometry/Outline")
		(27 "Margin" user)
		(31 "F.CrtYd" user "Package Geometry/Place Bound Top")
		(29 "B.CrtYd" user "Package Geometry/Place Bound Bottom")
		(35 "F.Fab" user "Ref Des/Assembly Top")
		(33 "B.Fab" user "Ref Des/Assembly Bottom")
	)
	(footprint ""
		(layer "B.Cu")
		(at 371.646958 -245.868952 -90)
		(property "Reference" "C2198"
			(at 0 0 90)
			(layer "B.SilkS")
			(hide yes)
			(effects
				(font
					(size 1.27 1.27)
				)
				(justify mirror)
			)
		)
		(property "Value" ""
			(at 0 0 90)
			(layer "B.Fab")
			(effects
				(font
					(size 1.27 1.27)
				)
				(justify mirror)
			)
		)
		(duplicate_pad_numbers_are_jumpers no)
		(fp_line
			(start -0.7874 0.4064)
			(end 0.7874 0.4064)
			(stroke
				(width 0.1524)
				(type default)
			)
			(layer "B.SilkS")
		)
		(fp_line
			(start 0.7874 0.4064)
			(end 0.7874 -0.4064)
			(stroke
				(width 0.1524)
				(type default)
			)
			(layer "B.SilkS")
		)
		(fp_line
			(start -0.7874 -0.4064)
			(end -0.7874 0.4064)
			(stroke
				(width 0.1524)
				(type default)
			)
			(layer "B.SilkS")
		)
		(fp_line
			(start 0.7874 -0.4064)
			(end -0.7874 -0.4064)
			(stroke
				(width 0.1524)
				(type default)
			)
			(layer "B.SilkS")
		)
		(fp_line
			(start -0.67945 0.3048)
			(end -0.120396 0.3048)
			(stroke
				(width 0.1)
				(type default)
			)
			(layer "B.Fab")
		)
		(fp_line
			(start -0.120396 0.3048)
			(end -0.120396 0.2794)
			(stroke
				(width 0.1)
				(type default)
			)
			(layer "B.Fab")
		)
		(fp_line
			(start 0.12065 0.3048)
			(end 0.67945 0.3048)
			(stroke
				(width 0.1)
				(type default)
			)
			(layer "B.Fab")
		)
		(fp_line
			(start 0.67945 0.3048)
			(end 0.67945 -0.305054)
			(stroke
				(width 0.1)
				(type default)
			)
			(layer "B.Fab")
		)
		(fp_line
			(start -0.120396 0.2794)
			(end 0.12065 0.2794)
			(stroke
				(width 0.1)
				(type default)
			)
			(layer "B.Fab")
		)
		(fp_line
			(start 0.12065 0.2794)
			(end 0.12065 0.3048)
			(stroke
				(width 0.1)
				(type default)
			)
			(layer "B.Fab")
		)
		(fp_line
			(start -0.12065 -0.2794)
			(end -0.12065 -0.3048)
			(stroke
				(width 0.1)
				(type default)
			)
			(layer "B.Fab")
		)
		(fp_line
			(start 0.12065 -0.2794)
			(end -0.12065 -0.2794)
			(stroke
				(width 0.1)
				(type default)
			)
			(layer "B.Fab")
		)
		(fp_line
			(start -0.67945 -0.3048)
			(end -0.67945 0.3048)
			(stroke
				(width 0.1)
				(type default)
			)
			(layer "B.Fab")
		)
		(fp_line
			(start -0.12065 -0.3048)
			(end -0.67945 -0.3048)
			(stroke
				(width 0.1)
				(type default)
			)
			(layer "B.Fab")
		)
		(fp_line
			(start 0.12065 -0.305054)
			(end 0.12065 -0.2794)
			(stroke
				(width 0.1)
				(type default)
			)
			(layer "B.Fab")
		)
		(fp_line
			(start 0.67945 -0.305054)
			(end 0.12065 -0.305054)
			(stroke
				(width 0.1)
				(type default)
			)
			(layer "B.Fab")
		)
		(pad "1" smd circle
			(at 0.40005 0 90)
			(size 0 0)
			(layers "B.Cu" "B.Mask" "B.Paste")
			(net "PVDDCR_CPU0_P0")
		)
		(pad "2" smd circle
			(at -0.40005 0 90)
			(size 0 0)
			(layers "B.Cu" "B.Mask" "B.Paste")
			(net "GND")
		)
	)
	(footprint ""
		(layer "B.Cu")
		(at 82.319114 -390.560052 90)
		(property "Reference" "C325"
			(at 0 0 90)
			(layer "B.SilkS")
			(hide yes)
			(effects
				(font
					(size 1.27 1.27)
				)
				(justify mirror)
			)
		)
		(property "Value" ""
			(at 0 0 90)
			(layer "B.Fab")
			(effects
				(font
					(size 1.27 1.27)
				)
				(justify mirror)
			)
		)
		(duplicate_pad_numbers_are_jumpers no)
		(fp_line
			(start 0.7874 -0.4064)
			(end -0.7874 -0.4064)
			(stroke
				(width 0.1524)
				(type default)
			)
			(layer "B.SilkS")
		)
		(fp_line
			(start -0.7874 -0.4064)
			(end -0.7874 0.4064)
			(stroke
				(width 0.1524)
				(type default)
			)
			(layer "B.SilkS")
		)
		(fp_line
			(start 0.7874 0.4064)
			(end 0.7874 -0.4064)
			(stroke
				(width 0.1524)
				(type default)
			)
			(layer "B.SilkS")
		)
		(fp_line
			(start -0.7874 0.4064)
			(end 0.7874 0.4064)
			(stroke
				(width 0.1524)
				(type default)
			)
			(layer "B.SilkS")
		)
		(fp_line
			(start 0.67945 -0.305054)
			(end 0.12065 -0.305054)
			(stroke
				(width 0.1)
				(type default)
			)
			(layer "B.Fab")
		)
		(fp_line
			(start 0.12065 -0.305054)
			(end 0.12065 -0.2794)
			(stroke
				(width 0.1)
				(type default)
			)
			(layer "B.Fab")
		)
		(fp_line
			(start -0.12065 -0.3048)
			(end -0.67945 -0.3048)
			(stroke
				(width 0.1)
				(type default)
			)
			(layer "B.Fab")
		)
		(fp_line
			(start -0.67945 -0.3048)
			(end -0.67945 0.3048)
			(stroke
				(width 0.1)
				(type default)
			)
			(layer "B.Fab")
		)
		(fp_line
			(start 0.12065 -0.2794)
			(end -0.12065 -0.2794)
			(stroke
				(width 0.1)
				(type default)
			)
			(layer "B.Fab")
		)
		(fp_line
			(start -0.12065 -0.2794)
			(end -0.12065 -0.3048)
			(stroke
				(width 0.1)
				(type default)
			)
			(layer "B.Fab")
		)
		(fp_line
			(start 0.12065 0.2794)
			(end 0.12065 0.3048)
			(stroke
				(width 0.1)
				(type default)
			)
			(layer "B.Fab")
		)
		(fp_line
			(start -0.120396 0.2794)
			(end 0.12065 0.2794)
			(stroke
				(width 0.1)
				(type default)
			)
			(layer "B.Fab")
		)
		(fp_line
			(start 0.67945 0.3048)
			(end 0.67945 -0.305054)
			(stroke
				(width 0.1)
				(type default)
			)
			(layer "B.Fab")
		)
		(fp_line
			(start 0.12065 0.3048)
			(end 0.67945 0.3048)
			(stroke
				(width 0.1)
				(type default)
			)
			(layer "B.Fab")
		)
		(fp_line
			(start -0.120396 0.3048)
			(end -0.120396 0.2794)
			(stroke
				(width 0.1)
				(type default)
			)
			(layer "B.Fab")
		)
		(fp_line
			(start -0.67945 0.3048)
			(end -0.120396 0.3048)
			(stroke
				(width 0.1)
				(type default)
			)
			(layer "B.Fab")
		)
		(pad "1" smd circle
			(at 0.40005 0 270)
			(size 0 0)
			(layers "B.Cu" "B.Mask" "B.Paste")
			(net "P0V9_CPU1_RT1_2A")
		)
		(pad "2" smd circle
			(at -0.40005 0 270)
			(size 0 0)
			(layers "B.Cu" "B.Mask" "B.Paste")
			(net "GND")
		)
	)
	(footprint ""
		(layer "B.Cu")
		(at 418.348922 -416.899344 90)
		(property "Reference" "C6628"
			(at 0 0 90)
			(layer "B.SilkS")
			(hide yes)
			(effects
				(font
					(size 1.27 1.27)
				)
				(justify mirror)
			)
		)
		(property "Value" ""
			(at 0 0 90)
			(layer "B.Fab")
			(effects
				(font
					(size 1.27 1.27)
				)
				(justify mirror)
			)
		)
		(duplicate_pad_numbers_are_jumpers no)
		(fp_line
			(start 0.299974 -0.150114)
			(end -0.299974 -0.150114)
			(stroke
				(width 0.1)
				(type default)
			)
			(layer "B.Fab")
		)
		(fp_line
			(start -0.299974 -0.150114)
			(end -0.299974 0.150114)
			(stroke
				(width 0.1)
				(type default)
			)
			(layer "B.Fab")
		)
		(fp_line
			(start 0.299974 0.150114)
			(end 0.299974 -0.150114)
			(stroke
				(width 0.1)
				(type default)
			)
			(layer "B.Fab")
		)
		(fp_line
			(start -0.299974 0.150114)
			(end 0.299974 0.150114)
			(stroke
				(width 0.1)
				(type default)
			)
			(layer "B.Fab")
		)
		(pad "1" smd rect
			(at 0.2667 0 270)
			(size 0.3048 0.381)
			(layers "B.Cu" "B.Mask" "B.Paste")
			(net "P5E_CPU0_P3_TX_BUF_C_DN<15>")
		)
		(pad "2" smd rect
			(at -0.2667 0 270)
			(size 0.3048 0.381)
			(layers "B.Cu" "B.Mask" "B.Paste")
			(net "P5E_CPU0_P3_TX_BUF_DN<15>")
		)
	)
)
